(kicad_pcb
	(version 20260206)
	(generator "pcbnew")
	(generator_version "10.0")
	(general
		(thickness 1.6)
		(legacy_teardrops no)
	)
	(paper "A4")
	(title_block
		(title "Bryce Canyon_F.DPB_16315-1-OCP.brd")
		(comment 1 "Bryce Canyon / footprints 334-339 of 2223")
	)
	(layers
		(0 "F.Cu" signal "TOP")
		(4 "In1.Cu" signal "L2GND")
		(6 "In2.Cu" signal "L3")
		(8 "In3.Cu" signal "L4GND")
		(10 "In4.Cu" signal "L5")
		(12 "In5.Cu" signal "L6VCC")
		(14 "In6.Cu" signal "L7VCC")
		(16 "In7.Cu" signal "L8")
		(18 "In8.Cu" signal "L9GND")
		(20 "In9.Cu" signal "L10")
		(22 "In10.Cu" signal "L11GND")
		(2 "B.Cu" signal "BOTTOM")
		(9 "F.Adhes" user "F.Adhesive")
		(11 "B.Adhes" user "B.Adhesive")
		(13 "F.Paste" user "Package Geometry/Pastemask Top")
		(15 "B.Paste" user "Package Geometry/Pastemask Bottom")
		(5 "F.SilkS" user "Ref Des/Silkscreen Top")
		(7 "B.SilkS" user "Ref Des/Silkscreen Bottom")
		(1 "F.Mask" user "Board Geometry/Soldermask Top")
		(3 "B.Mask" user "Board Geometry/Soldermask Bottom")
		(17 "Dwgs.User" user "User.Drawings")
		(19 "Cmts.User" user "User.Comments")
		(21 "Eco1.User" user "User.Eco1")
		(23 "Eco2.User" user "User.Eco2")
		(25 "Edge.Cuts" user "Board Geometry/Outline")
		(27 "Margin" user)
		(31 "F.CrtYd" user "Package Geometry/Place Bound Top")
		(29 "B.CrtYd" user "Package Geometry/Place Bound Bottom")
		(35 "F.Fab" user "Ref Des/Assembly Top")
		(33 "B.Fab" user "Ref Des/Assembly Bottom")
	)
	(footprint ""
		(layer "F.Cu")
		(at 35.797998 -291.127942 90)
		(property "Reference" "C513"
			(at 0 0 90)
			(layer "F.SilkS")
			(hide yes)
			(effects
				(font
					(size 1.27 1.27)
				)
			)
		)
		(property "Value" "SCD01U50V2KX-1GP"
			(at 1.1811 -2.7051 90)
			(unlocked yes)
			(layer "F.Fab")
			(hide yes)
			(effects
				(font
					(size 1.016 1.016)
					(thickness 0.1524)
				)
			)
		)
		(property "Device Type" "C402H22"
			(at 1.1811 -4.2291 90)
			(unlocked yes)
			(layer "F.Fab")
			(hide yes)
			(effects
				(font
					(size 1.016 1.016)
					(thickness 0.1524)
				)
			)
		)
		(duplicate_pad_numbers_are_jumpers no)
		(fp_rect
			(start -0.4318 0.9525)
			(end 0.4318 -0.9525)
			(stroke
				(width 0)
				(type default)
			)
			(fill no)
			(layer "F.CrtYd")
		)
		(fp_rect
			(start -0.4318 0.9525)
			(end 0.4318 -0.9525)
			(stroke
				(width 0)
				(type default)
			)
			(fill no)
			(layer "F.Fab")
		)
		(pad "1" smd custom
			(at 0 -0.4445 90)
			(size 0.1524 0.1524)
			(layers "F.Cu" "F.Mask" "F.Paste")
			(net "HDD_PRSNT_0")
			(options
				(clearance outline)
				(anchor circle)
			)
			(primitives
				(gr_poly
					(pts
						(arc
							(start 0.3048 -0.2032)
							(mid 0.275042 -0.275042)
							(end 0.2032 -0.3048)
						)
						(arc
							(start -0.2032 -0.3048)
							(mid -0.275042 -0.275042)
							(end -0.3048 -0.2032)
						)
						(arc
							(start -0.3048 0.2032)
							(mid -0.275042 0.275042)
							(end -0.2032 0.3048)
						)
						(arc
							(start 0.2032 0.3048)
							(mid 0.275042 0.275042)
							(end 0.3048 0.2032)
						)
					)
					(width 0)
					(fill yes)
				)
			)
		)
		(pad "2" smd custom
			(at 0 0.4445 90)
			(size 0.1524 0.1524)
			(layers "F.Cu" "F.Mask" "F.Paste")
			(net "GND")
			(options
				(clearance outline)
				(anchor circle)
			)
			(primitives
				(gr_poly
					(pts
						(arc
							(start 0.3048 -0.2032)
							(mid 0.275042 -0.275042)
							(end 0.2032 -0.3048)
						)
						(arc
							(start -0.2032 -0.3048)
							(mid -0.275042 -0.275042)
							(end -0.3048 -0.2032)
						)
						(arc
							(start -0.3048 0.2032)
							(mid -0.275042 0.275042)
							(end -0.2032 0.3048)
						)
						(arc
							(start 0.2032 0.3048)
							(mid 0.275042 0.275042)
							(end 0.3048 0.2032)
						)
					)
					(width 0)
					(fill yes)
				)
			)
		)
	)
	(footprint ""
		(layer "F.Cu")
		(at 382.787398 -134.849362 180)
		(property "Reference" "R1295"
			(at 0 0 180)
			(layer "F.SilkS")
			(hide yes)
			(effects
				(font
					(size 1.27 1.27)
				)
			)
		)
		(property "Value" "3K3R3F-GP"
			(at -0.0254 -2.5146 180)
			(unlocked yes)
			(layer "F.Fab")
			(hide yes)
			(effects
				(font
					(size 1.016 1.016)
					(thickness 0.1524)
				)
			)
		)
		(property "Device Type" "R603H22"
			(at -0.0254 -4.0386 180)
			(unlocked yes)
			(layer "F.Fab")
			(hide yes)
			(effects
				(font
					(size 1.016 1.016)
					(thickness 0.1524)
				)
			)
		)
		(duplicate_pad_numbers_are_jumpers no)
		(fp_line
			(start 0.2032 0)
			(end 0.4826 0)
			(stroke
				(width 0.2032)
				(type default)
			)
			(layer "F.SilkS")
		)
		(fp_line
			(start -0.4826 0)
			(end -0.2032 0)
			(stroke
				(width 0.2032)
				(type default)
			)
			(layer "F.SilkS")
		)
		(fp_rect
			(start -0.5842 1.3335)
			(end 0.5842 -1.3335)
			(stroke
				(width 0)
				(type default)
			)
			(fill no)
			(layer "F.CrtYd")
		)
		(fp_rect
			(start -0.5842 1.3335)
			(end 0.5842 -1.3335)
			(stroke
				(width 0)
				(type default)
			)
			(fill no)
			(layer "F.Fab")
		)
		(pad "1" smd custom
			(at 0 -0.762 180)
			(size 0.2159 0.2159)
			(layers "F.Cu" "F.Mask" "F.Paste")
			(net "P12V_B")
			(options
				(clearance outline)
				(anchor circle)
			)
			(primitives
				(gr_poly
					(pts
						(arc
							(start -0.3302 -0.4318)
							(mid -0.402042 -0.402042)
							(end -0.4318 -0.3302)
						)
						(arc
							(start -0.4318 0.3302)
							(mid -0.402042 0.402042)
							(end -0.3302 0.4318)
						)
						(arc
							(start 0.3302 0.4318)
							(mid 0.402042 0.402042)
							(end 0.4318 0.3302)
						)
						(arc
							(start 0.4318 -0.3302)
							(mid 0.402042 -0.402042)
							(end 0.3302 -0.4318)
						)
					)
					(width 0)
					(fill yes)
				)
			)
		)
		(pad "2" smd custom
			(at 0 0.762 180)
			(size 0.2159 0.2159)
			(layers "F.Cu" "F.Mask" "F.Paste")
			(net "VCCP_B")
			(options
				(clearance outline)
				(anchor circle)
			)
			(primitives
				(gr_poly
					(pts
						(arc
							(start -0.3302 -0.4318)
							(mid -0.402042 -0.402042)
							(end -0.4318 -0.3302)
						)
						(arc
							(start -0.4318 0.3302)
							(mid -0.402042 0.402042)
							(end -0.3302 0.4318)
						)
						(arc
							(start 0.3302 0.4318)
							(mid 0.402042 0.402042)
							(end 0.4318 0.3302)
						)
						(arc
							(start 0.4318 -0.3302)
							(mid 0.402042 -0.402042)
							(end 0.3302 -0.4318)
						)
					)
					(width 0)
					(fill yes)
				)
			)
		)
	)
	(footprint ""
		(layer "F.Cu")
		(at 330.67498 -92.799916)
		(property "Reference" ""
			(at 0 0 0)
			(layer "F.SilkS")
			(hide yes)
			(effects
				(font
					(size 1.27 1.27)
				)
			)
		)
		(property "Value" "*"
			(at -8.398764 -8.057642 0)
			(unlocked yes)
			(layer "F.Fab")
			(hide yes)
			(effects
				(font
					(size 1.016 1.016)
					(thickness 0.1524)
				)
			)
		)
		(duplicate_pad_numbers_are_jumpers no)
		(fp_poly
			(pts
				(arc
					(start 7.3152 0)
					(mid 0 7.3152)
					(end -7.3152 0)
				)
				(arc
					(start -7.3152 -5.9944)
					(mid 0 -13.3096)
					(end 7.3152 -5.9944)
				)
			)
			(stroke
				(width 0)
				(type default)
			)
			(fill no)
			(layer "B.CrtYd")
		)
		(fp_poly
			(pts
				(arc
					(start 7.3152 0)
					(mid 0 7.3152)
					(end -7.3152 0)
				)
				(arc
					(start -7.3152 -5.9944)
					(mid 0 -13.3096)
					(end 7.3152 -5.9944)
				)
			)
			(stroke
				(width 0)
				(type default)
			)
			(fill no)
			(layer "F.CrtYd")
		)
		(fp_poly
			(pts
				(arc
					(start 7.3152 0)
					(mid 0 7.3152)
					(end -7.3152 0)
				)
				(arc
					(start -7.3152 -5.9944)
					(mid 0 -13.3096)
					(end 7.3152 -5.9944)
				)
			)
			(stroke
				(width 0)
				(type default)
			)
			(fill no)
			(layer "B.Fab")
		)
		(fp_poly
			(pts
				(arc
					(start 7.3152 0)
					(mid 0 7.3152)
					(end -7.3152 0)
				)
				(arc
					(start -7.3152 -5.9944)
					(mid 0 -13.3096)
					(end 7.3152 -5.9944)
				)
			)
			(stroke
				(width 0)
				(type default)
			)
			(fill no)
			(layer "F.Fab")
		)
		(pad "1" thru_hole oval
			(at 0 0)
			(size 14.0208 20.0152)
			(drill 0.0254
				(offset 0 -2.9972)
			)
			(layers "*.Cu" "*.Mask")
			(remove_unused_layers no)
			(net "Net_102")
			(clearance -1.002284)
			(thermal_gap 0.1524)
			(padstack
				(mode front_inner_back)
				(layer "Inner"
					(shape custom)
					(size 2.928012 2.928012)
					(options
						(anchor circle)
					)
					(primitives
						(gr_poly
							(pts
								(arc
									(start 4.571746 -2.084324)
									(mid 0.000333 7.430372)
									(end -4.571492 -2.084324)
								)
								(arc
									(start -4.571492 -2.084324)
									(mid -3.570296 -3.611977)
									(end -2.875026 -5.30098)
								)
								(arc
									(start -2.875026 -5.30098)
									(mid 0.000217 -7.43089)
									(end 2.87528 -5.30098)
								)
								(arc
									(start 2.87528 -5.30098)
									(mid 3.570511 -3.611956)
									(end 4.571746 -2.084324)
								)
							)
							(width 0)
							(fill yes)
						)
					)
					(clearance 0.1524)
				)
				(layer "B.Cu"
					(shape oval)
					(size 14.0208 20.0152)
					(offset 0 -2.9972)
					(clearance -1.002284)
				)
			)
		)
		(zone
			(layers "F.Cu" "B.Cu" "In1.Cu" "In2.Cu" "In3.Cu" "In4.Cu" "In5.Cu" "In6.Cu"
				"In7.Cu" "In8.Cu" "In9.Cu" "In10.Cu"
			)
			(hatch none 0.5)
			(connect_pads
				(clearance 0)
			)
			(min_thickness 0.25)
			(keepout
				(tracks not_allowed)
				(vias allowed)
				(pads allowed)
				(copperpour not_allowed)
				(footprints allowed)
			)
			(placement
				(enabled no)
				(sheetname "")
			)
			(fill
				(thermal_gap 0.5)
				(thermal_bridge_width 0.5)
				(island_removal_mode 0)
			)
			(polygon
				(pts
					(arc
						(start 323.66458 -98.794316)
						(mid 330.67498 -105.804716)
						(end 337.68538 -98.794316)
					)
					(arc
						(start 337.68538 -92.799916)
						(mid 330.67498 -85.789516)
						(end 323.66458 -92.799916)
					)
				)
			)
		)
	)
	(footprint ""
		(layer "F.Cu")
		(at 467.635336 -294.315134 180)
		(property "Reference" "R326"
			(at 0 0 180)
			(layer "F.SilkS")
			(hide yes)
			(effects
				(font
					(size 1.27 1.27)
				)
			)
		)
		(property "Value" "130R3F-GP"
			(at -0.0254 -2.5146 180)
			(unlocked yes)
			(layer "F.Fab")
			(hide yes)
			(effects
				(font
					(size 1.016 1.016)
					(thickness 0.1524)
				)
			)
		)
		(property "Device Type" "R603H22"
			(at -0.0254 -4.0386 180)
			(unlocked yes)
			(layer "F.Fab")
			(hide yes)
			(effects
				(font
					(size 1.016 1.016)
					(thickness 0.1524)
				)
			)
		)
		(duplicate_pad_numbers_are_jumpers no)
		(fp_line
			(start 0.2032 0)
			(end 0.4826 0)
			(stroke
				(width 0.2032)
				(type default)
			)
			(layer "F.SilkS")
		)
		(fp_line
			(start -0.4826 0)
			(end -0.2032 0)
			(stroke
				(width 0.2032)
				(type default)
			)
			(layer "F.SilkS")
		)
		(fp_rect
			(start -0.5842 1.3335)
			(end 0.5842 -1.3335)
			(stroke
				(width 0)
				(type default)
			)
			(fill no)
			(layer "F.CrtYd")
		)
		(fp_rect
			(start -0.5842 1.3335)
			(end 0.5842 -1.3335)
			(stroke
				(width 0)
				(type default)
			)
			(fill no)
			(layer "F.Fab")
		)
		(pad "1" smd custom
			(at 0 -0.762 180)
			(size 0.2159 0.2159)
			(layers "F.Cu" "F.Mask" "F.Paste")
			(net "P5V_B")
			(options
				(clearance outline)
				(anchor circle)
			)
			(primitives
				(gr_poly
					(pts
						(arc
							(start -0.3302 -0.4318)
							(mid -0.402042 -0.402042)
							(end -0.4318 -0.3302)
						)
						(arc
							(start -0.4318 0.3302)
							(mid -0.402042 0.402042)
							(end -0.3302 0.4318)
						)
						(arc
							(start 0.3302 0.4318)
							(mid 0.402042 0.402042)
							(end 0.4318 0.3302)
						)
						(arc
							(start 0.4318 -0.3302)
							(mid 0.402042 -0.402042)
							(end 0.3302 -0.4318)
						)
					)
					(width 0)
					(fill yes)
				)
			)
		)
		(pad "2" smd custom
			(at 0 0.762 180)
			(size 0.2159 0.2159)
			(layers "F.Cu" "F.Mask" "F.Paste")
			(net "FLT_HDD35")
			(options
				(clearance outline)
				(anchor circle)
			)
			(primitives
				(gr_poly
					(pts
						(arc
							(start -0.3302 -0.4318)
							(mid -0.402042 -0.402042)
							(end -0.4318 -0.3302)
						)
						(arc
							(start -0.4318 0.3302)
							(mid -0.402042 0.402042)
							(end -0.3302 0.4318)
						)
						(arc
							(start 0.3302 0.4318)
							(mid 0.402042 0.402042)
							(end 0.4318 0.3302)
						)
						(arc
							(start 0.4318 -0.3302)
							(mid 0.402042 -0.402042)
							(end 0.3302 -0.4318)
						)
					)
					(width 0)
					(fill yes)
				)
			)
		)
	)
	(footprint ""
		(layer "F.Cu")
		(at 159.324802 -92.799916)
		(property "Reference" ""
			(at 0 0 0)
			(layer "F.SilkS")
			(hide yes)
			(effects
				(font
					(size 1.27 1.27)
				)
			)
		)
		(property "Value" "*"
			(at -8.398764 -8.057642 0)
			(unlocked yes)
			(layer "F.Fab")
			(hide yes)
			(effects
				(font
					(size 1.016 1.016)
					(thickness 0.1524)
				)
			)
		)
		(duplicate_pad_numbers_are_jumpers no)
		(fp_poly
			(pts
				(arc
					(start 7.3152 0)
					(mid 0 7.3152)
					(end -7.3152 0)
				)
				(arc
					(start -7.3152 -5.9944)
					(mid 0 -13.3096)
					(end 7.3152 -5.9944)
				)
			)
			(stroke
				(width 0)
				(type default)
			)
			(fill no)
			(layer "B.CrtYd")
		)
		(fp_poly
			(pts
				(arc
					(start 7.3152 0)
					(mid 0 7.3152)
					(end -7.3152 0)
				)
				(arc
					(start -7.3152 -5.9944)
					(mid 0 -13.3096)
					(end 7.3152 -5.9944)
				)
			)
			(stroke
				(width 0)
				(type default)
			)
			(fill no)
			(layer "F.CrtYd")
		)
		(fp_poly
			(pts
				(arc
					(start 7.3152 0)
					(mid 0 7.3152)
					(end -7.3152 0)
				)
				(arc
					(start -7.3152 -5.9944)
					(mid 0 -13.3096)
					(end 7.3152 -5.9944)
				)
			)
			(stroke
				(width 0)
				(type default)
			)
			(fill no)
			(layer "B.Fab")
		)
		(fp_poly
			(pts
				(arc
					(start 7.3152 0)
					(mid 0 7.3152)
					(end -7.3152 0)
				)
				(arc
					(start -7.3152 -5.9944)
					(mid 0 -13.3096)
					(end 7.3152 -5.9944)
				)
			)
			(stroke
				(width 0)
				(type default)
			)
			(fill no)
			(layer "F.Fab")
		)
		(pad "1" thru_hole oval
			(at 0 0)
			(size 14.0208 20.0152)
			(drill 0.0254
				(offset 0 -2.9972)
			)
			(layers "*.Cu" "*.Mask")
			(remove_unused_layers no)
			(net "Net_26")
			(clearance -1.002284)
			(thermal_gap 0.1524)
			(padstack
				(mode front_inner_back)
				(layer "Inner"
					(shape custom)
					(size 2.928012 2.928012)
					(options
						(anchor circle)
					)
					(primitives
						(gr_poly
							(pts
								(arc
									(start 4.571746 -2.084324)
									(mid 0.000333 7.430372)
									(end -4.571492 -2.084324)
								)
								(arc
									(start -4.571492 -2.084324)
									(mid -3.570296 -3.611977)
									(end -2.875026 -5.30098)
								)
								(arc
									(start -2.875026 -5.30098)
									(mid 0.000217 -7.43089)
									(end 2.87528 -5.30098)
								)
								(arc
									(start 2.87528 -5.30098)
									(mid 3.570511 -3.611956)
									(end 4.571746 -2.084324)
								)
							)
							(width 0)
							(fill yes)
						)
					)
					(clearance 0.1524)
				)
				(layer "B.Cu"
					(shape oval)
					(size 14.0208 20.0152)
					(offset 0 -2.9972)
					(clearance -1.002284)
				)
			)
		)
		(zone
			(layers "F.Cu" "B.Cu" "In1.Cu" "In2.Cu" "In3.Cu" "In4.Cu" "In5.Cu" "In6.Cu"
				"In7.Cu" "In8.Cu" "In9.Cu" "In10.Cu"
			)
			(hatch none 0.5)
			(connect_pads
				(clearance 0)
			)
			(min_thickness 0.25)
			(keepout
				(tracks not_allowed)
				(vias allowed)
				(pads allowed)
				(copperpour not_allowed)
				(footprints allowed)
			)
			(placement
				(enabled no)
				(sheetname "")
			)
			(fill
				(thermal_gap 0.5)
				(thermal_bridge_width 0.5)
				(island_removal_mode 0)
			)
			(polygon
				(pts
					(arc
						(start 152.314402 -98.794316)
						(mid 159.324802 -105.804716)
						(end 166.335202 -98.794316)
					)
					(arc
						(start 166.335202 -92.799916)
						(mid 159.324802 -85.789516)
						(end 152.314402 -92.799916)
					)
				)
			)
		)
	)
	(footprint ""
		(layer "F.Cu")
		(at 180.7464 -163.554918 90)
		(property "Reference" "R533"
			(at 0 0 90)
			(layer "F.SilkS")
			(hide yes)
			(effects
				(font
					(size 1.27 1.27)
				)
			)
		)
		(property "Value" "4K7R2J-2-GP"
			(at 0.064008 -3.993896 90)
			(unlocked yes)
			(layer "F.Fab")
			(hide yes)
			(effects
				(font
					(size 1.016 1.016)
					(thickness 0.1524)
				)
			)
		)
		(property "Device Type" "R402H16"
			(at 0.064008 -5.517896 90)
			(unlocked yes)
			(layer "F.Fab")
			(hide yes)
			(effects
				(font
					(size 1.016 1.016)
					(thickness 0.1524)
				)
			)
		)
		(duplicate_pad_numbers_are_jumpers no)
		(fp_line
			(start 0.508 -0.9398)
			(end -0.508 -0.9398)
			(stroke
				(width 0.1524)
				(type default)
			)
			(layer "F.SilkS")
		)
		(fp_line
			(start -0.508 -0.9398)
			(end -0.508 0.9398)
			(stroke
				(width 0.1524)
				(type default)
			)
			(layer "F.SilkS")
		)
		(fp_rect
			(start -0.508 0.9398)
			(end 0.508 -0.9398)
			(stroke
				(width 0)
				(type default)
			)
			(fill no)
			(layer "F.CrtYd")
		)
		(fp_rect
			(start -0.508 0.9398)
			(end 0.508 -0.9398)
			(stroke
				(width 0)
				(type default)
			)
			(fill no)
			(layer "F.Fab")
		)
		(pad "1" smd custom
			(at 0 -0.4445 90)
			(size 0.1397 0.1397)
			(layers "F.Cu" "F.Mask" "F.Paste")
			(net "SW_PWR_R_HDD17")
			(options
				(clearance outline)
				(anchor circle)
			)
			(primitives
				(gr_poly
					(pts
						(arc
							(start -0.1778 -0.2794)
							(mid -0.249642 -0.249642)
							(end -0.2794 -0.1778)
						)
						(arc
							(start -0.2794 0.1778)
							(mid -0.249642 0.249642)
							(end -0.1778 0.2794)
						)
						(arc
							(start 0.1778 0.2794)
							(mid 0.249642 0.249642)
							(end 0.2794 0.1778)
						)
						(arc
							(start 0.2794 -0.1778)
							(mid 0.249642 -0.249642)
							(end 0.1778 -0.2794)
						)
					)
					(width 0)
					(fill yes)
				)
			)
		)
		(pad "2" smd custom
			(at 0 0.4445 90)
			(size 0.1397 0.1397)
			(layers "F.Cu" "F.Mask" "F.Paste")
			(net "GND")
			(options
				(clearance outline)
				(anchor circle)
			)
			(primitives
				(gr_poly
					(pts
						(arc
							(start -0.1778 -0.2794)
							(mid -0.249642 -0.249642)
							(end -0.2794 -0.1778)
						)
						(arc
							(start -0.2794 0.1778)
							(mid -0.249642 0.249642)
							(end -0.1778 0.2794)
						)
						(arc
							(start 0.1778 0.2794)
							(mid 0.249642 0.249642)
							(end 0.2794 0.1778)
						)
						(arc
							(start 0.2794 -0.1778)
							(mid 0.249642 -0.249642)
							(end 0.1778 -0.2794)
						)
					)
					(width 0)
					(fill yes)
				)
			)
		)
	)
)
